Component Report
G:/<user>/F0T/9052_F0T_PDB_Converter_Brick_F/Board/TO/9052_F0T_PDB_Converter_Brick_F_V03_1208_1600.brd
Mon Dec 12 13:12:55 2022
Total Components:  572
REFDES,COMP_DEVICE_TYPE,COMP_VALUE,COMP_TOL,COMP_PACKAGE,SYM_X,SYM_Y,SYM_ROTATE,SYM_MIRROR
C1,CAP_NP_16V_C0402-0201_DISCRETE_,0.1UF,,C0402-0201,9331.96,3138.85,90.000,YES
C4,CAP_NP_16V_C0402-0201_DISCRETE_,0.1UF,,C0402-0201,8110.00,2745.00,90.000,YES
C5,CAP_NP_16V_C0402-0201_DISCRETE_,0.1UF,,C0402-0201,9125.00,3240.00,270.000,YES
C7,CAP_NP_16V_C0402-0201_DISCRETE_,0.1UF,,C0402-0201,8325.00,3565.00,90.000,YES
C8,CAP_NP_16V_C0402-0201_DISCRETE_,0.1UF,,C0402-0201,8530.00,3585.00,90.000,YES
C9,CAP_NP_16V_C0402-0201_DISCRETE_,0.1UF,,C0402-0201,9245.00,3595.00,90.000,YES
C10,CAP_NP_16V_C0402-0201_DISCRETE_,0.1UF,,C0402-0201,8830.00,3545.00,90.000,YES
C14,CAP_NP_16V_C0402-0201_DISCRETE_,0.1UF,,C0402-0201,9330.00,2895.00,270.000,YES
C15,CAP_NP_16V_C0402-0201_DISCRETE_,0.1UF,,C0402-0201,9155.00,2795.00,270.000,YES
C16,CAP_NP_16V_C0402-0201_DISCRETE_,0.1UF,,C0402-0201,8775.00,2795.00,270.000,YES
C17,CAP_NP_16V_C0402-0201_DISCRETE_,0.1UF,,C0402-0201,9050.00,2795.00,270.000,YES
C18,CAP_NP_16V_C0402-0201_DISCRETE_,0.1UF,,C0402-0201,8840.00,2795.00,270.000,YES
C22,CAP_NP_100V_C1206_H76_CH5228K12,2.2UF,,C1206_H76,8850.00,3760.00,90.000,YES
C23,CAP_NP_100V_C1206_H76_CH5228K12,2.2UF,,C1206_H76,8490.00,3760.00,270.000,NO
C24,CAP_NP_100V_C1206_H76_CH5228K12,2.2UF,,C1206_H76,8945.00,3760.00,90.000,YES
C25,CAP_NP_100V_C1206_H76_CH5228K12,2.2UF,,C1206_H76,8580.00,3760.00,270.000,NO
C26,CAP_NP_100V_C1206_H76_CH5228K12,2.2UF,,C1206_H76,9040.00,3760.00,90.000,YES
C27,CAP_NP_100V_C1206_H76_CH5228K12,2.2UF,,C1206_H76,8670.00,3760.00,270.000,NO
C28,CAP_NP_100V_C1206_H76_CH5228K12,2.2UF,,C1206_H76,9135.00,3760.00,90.000,YES
C29,CAP_NP_100V_C1206_H76_CH5228K12,2.2UF,,C1206_H76,8760.00,3760.00,270.000,NO
C30,CAP_NP_100V_C1206_H76_CH5228K12,2.2UF,,C1206_H76,9235.00,3760.00,90.000,YES
C31,CAP_NP_100V_C1206_H76_CH5228K12,2.2UF,,C1206_H76,8855.00,3760.00,270.000,NO
C32,CAP_NP_100V_C1206_H76_CH5228K12,2.2UF,,C1206_H76,9330.00,3760.00,90.000,YES
C33,CAP_NP_100V_C1206_H76_CH5228K12,2.2UF,,C1206_H76,8950.00,3760.00,270.000,NO
C34,CAP_NP_100V_C1206_H76_CH5228K12,2.2UF,,C1206_H76,9425.00,3760.00,90.000,YES
C35,CAP_NP_100V_C1206_H76_CH5228K12,2.2UF,,C1206_H76,9045.00,3760.00,270.000,NO
C36,CAP_NP_100V_C1206_H76_CH5228K12,2.2UF,,C1206_H76,9520.00,3760.00,90.000,YES
C37,CAP_NP_100V_C1206_H76_CH5228K12,2.2UF,,C1206_H76,9140.00,3760.00,270.000,NO
C38,CAP_NP_100V_C1206_H76_CH5228K12,2.2UF,,C1206_H76,8755.00,3760.00,90.000,YES
C39,CAP_NP_100V_C1206_H76_CH5228K12,2.2UF,,C1206_H76,9235.00,3760.00,270.000,NO
C40,CAP_NP_100V_C1206_H76_CH5228K12,2.2UF,,C1206_H76,8660.00,3760.00,90.000,YES
C41,CAP_NP_100V_C1206_H76_CH5228K12,2.2UF,,C1206_H76,9330.00,3760.00,270.000,NO
C42,CAP_NP_100V_C1206_H76_CH5228K12,2.2UF,,C1206_H76,8565.00,3760.00,90.000,YES
C43,CAP_NP_100V_C1206_H76_CH5228K12,2.2UF,,C1206_H76,9425.00,3760.00,270.000,NO
C44,CAP_NP_100V_C1206_H76_CH5228K12,2.2UF,,C1206_H76,8470.00,3760.00,90.000,YES
C45,CAP_NP_100V_C1206_H76_CH5228K12,2.2UF,,C1206_H76,9520.00,3760.00,270.000,NO
C47,CAP_NP_16V_C0402-0201_DISCRETE_,0.1UF,,C0402-0201,8945.00,2795.00,270.000,YES
C48,CAP_NP_16V_C0402-0201_DISCRETE_,0.1UF,,C0402-0201,7465.00,3615.00,0.000,YES
C51,CAP_NP_16V_C0402-0201_DISCRETE_,0.1UF,,C0402-0201,5387.80,4490.00,90.000,YES
C52,CAP_NP_50V_C0402-0201_DISCRETE_,100PF,,C0402-0201,5295.00,3055.00,180.000,YES
C53,CAP_NP_50V_C0402-0201_DISCRETE_,100PF,,C0402-0201,5385.00,3055.00,180.000,YES
C54,CAP_NP_50V_C0402-0201_DISCRETE_,100PF,,C0402-0201,5475.00,3055.00,180.000,YES
C55,CAP_NP_16V_C0402-0201_DISCRETE_,0.1UF,,C0402-0201,5895.00,4505.00,270.000,YES
C56,CAP_NP_16V_C0402-0201_DISCRETE_,0.1UF,,C0402-0201,3812.99,4490.00,90.000,YES
C57,CAP_NP_50V_C0402-0201_DISCRETE_,100PF,,C0402-0201,3890.00,3050.00,180.000,YES
C58,CAP_NP_50V_C0402-0201_DISCRETE_,100PF,,C0402-0201,3715.00,3050.00,180.000,YES
C59,CAP_NP_50V_C0402-0201_DISCRETE_,100PF,,C0402-0201,3800.00,3050.00,180.000,YES
C60,CAP_NP_16V_C0402-0201_DISCRETE_,0.1UF,,C0402-0201,2238.19,4490.00,90.000,YES
C61,CAP_NP_50V_C0402-0201_DISCRETE_,100PF,,C0402-0201,2145.00,3050.00,180.000,YES
C62,CAP_NP_50V_C0402-0201_DISCRETE_,100PF,,C0402-0201,2230.00,3050.00,180.000,YES
C63,CAP_NP_50V_C0402-0201_DISCRETE_,100PF,,C0402-0201,2320.00,3050.00,180.000,YES
C66,CAP_NP_16V_C0402-0201_DISCRETE_,0.1UF,,C0402-0201,9470.00,2895.00,270.000,YES
C67,CAP_NP_16V_C0402-0201_DISCRETE_,0.1UF,,C0402-0201,9400.00,2895.00,270.000,YES
C69,CAP_NP_100V_C0603_CH3108K1900_0,0.01UF,,C0603,11735.00,1055.00,0.000,NO
C70,CAP_NP_16V_C0402-0201_DISCRETE_,0.1UF,,C0402-0201,6962.61,4490.00,90.000,YES
C71,CAP_NP_50V_C0402-0201_DISCRETE_,100PF,,C0402-0201,6869.81,3055.00,180.000,YES
C72,CAP_NP_50V_C0402-0201_DISCRETE_,100PF,,C0402-0201,6959.81,3055.00,180.000,YES
C73,CAP_NP_50V_C0402-0201_DISCRETE_,100PF,,C0402-0201,7049.81,3055.00,180.000,YES
C74,CAP_NP_16V_C0402-0201_DISCRETE_,0.1UF,,C0402-0201,4320.19,4560.00,270.000,YES
C89,CAP_NP_100V_C0603_CH3108K1900_0,0.01UF,,C0603,11130.00,830.00,0.000,NO
C90,CAP_NP_16V_C0402-0201_DISCRETE_,0.1UF,,C0402-0201,10951.00,955.00,90.000,NO
C91,CAP_NP_25V_C0402_CH5104KEB02_1U,1UF,,C0402,1812.71,2110.76,90.000,NO
C92,CAP_NP_25V_C0805_H61_CH6104KEA0,10UF,,C0805_H61,1472.34,2360.63,270.000,YES
C93,CAP_NP_25V_C0402_CH4104K1B00_0.,0.1UF,,C0402,1531.80,2173.60,270.000,NO
C94,CAP_NP_25V_C0402-0201_CH4224K1B,0.22UF,,C0402-0201,1798.40,2208.30,0.000,NO
C95,CAP_NP_16V_C0603_H40_CH5223M190,2.2UF,,C0603_H40,1522.00,2383.00,270.000,NO
C96,CAP_NP_25V_C0402-0201_CH3474K1B,0.047UF,,C0402-0201,1798.40,2313.30,0.000,NO
C97,CAP_NP_50V_C0402-0201_CH4106K1B,100NF,,C0402-0201,1798.40,2383.30,0.000,NO
C98,CAP_NP_50V_C0402-0201_CH1566K1B,560PF,,C0402-0201,1798.74,2235.23,0.000,YES
C100,CAP_NP_25V_C0402-0201_CH5104KEB,1UF,,C0402-0201,11520.00,1540.00,180.000,YES
C101,CAP_NP_16V_C0805_H57_DISCRETE_C,22UF,,C0805_H57,10635.00,1210.00,270.000,YES
C102,CAP_NP_25V_C0402-0201_CH5104KEB,1UF,,C0402-0201,10720.00,1140.00,0.000,YES
D1,LED_0_LED2S_0402_IC_BEBL0172Z00,LED_BLUE,,LED2S_0402,8325.00,3290.00,180.000,NO
D2,LED_0_LED2S_0402_IC_BEBL0172Z00,LED_BLUE,,LED2S_0402,7978.54,2641.09,270.000,NO
D3,LED_0_LED2S_0402_IC_BEBL0172Z00,LED_BLUE,,LED2S_0402,8095.00,2640.00,270.000,NO
D4,SMDJ60A_D_SMBJ14A_IC_BCMBJ14AZ0,SMBJ14A,,D_SMBJ14A,1974.00,2237.00,270.000,NO
D5,SCHOTTKY_AC_D2010XF_IC_BC000340,B340A-13-F,,D2010XF,1260.00,2585.00,180.000,NO
D6,DIODE_SOD323XB_IC_BC000340033_S,SDMK0340L-7-F,,SOD323XB,11392.95,1497.34,180.000,YES
D11,SCHOTTKY_AC_D2010XF_IC_BC000340,B340A-13-F,,D2010XF,11080.00,1070.00,180.000,YES
D12,SCHOTTKY_AC_D2010XF_IC_BC000340,B340A-13-F,,D2010XF,10540.00,1005.00,180.000,YES
DM1,ME_DUMMY_SYMBOL_PNLABEL_23-5X5_,PNLABEL_23-5X5,,PNLABEL_23-5X5,2450.00,335.00,0.000,NO
FS1,FUSE_F4012_IO_DKK00XFU000_20A/1,20A/125V,,F4012,11831.00,1945.00,90.000,NO
H2,HOLE_HOLE_C10D3_5B10_OB22XC5_NP,HOLE_C10D3_5B10_OB22XC5_NPM_TEAR_SPD,,HOLE_C10D3_5B10_OB22XC5_NPM_TEAR_SPD,10305.00,5425.00,270.000,NO
H4,HOLE_HOLE_C10D3_5B10_OB22XC5_NP,HOLE_C10D3_5B10_OB22XC5_NPM_TEAR_SPD,,HOLE_C10D3_5B10_OB22XC5_NPM_TEAR_SPD,5118.11,472.44,270.000,NO
H11,HOLE_HOLE_C10D3_5B10_OB22XC5_NP,HOLE_C10D3_5B10_OB22XC5_NPM_TEAR_SPD,,HOLE_C10D3_5B10_OB22XC5_NPM_TEAR_SPD,1181.11,5354.33,270.000,NO
H14,HOLE_HOLE_C10D3_5B10_OB22XC5_NP,HOLE_C10D3_5B10_OB22XC5_NPM_TEAR_SPD,,HOLE_C10D3_5B10_OB22XC5_NPM_TEAR_SPD,9885.00,2280.00,270.000,NO
H16,HOLE_HOLE_C10D3_5B10_OB22XC5_NP,HOLE_C10D3_5B10_OB22XC5_NPM_TEAR_SPD,,HOLE_C10D3_5B10_OB22XC5_NPM_TEAR_SPD,1181.11,472.44,270.000,NO
H18,HOLE_HOLE_C10D3_5B10_OB22XC5_NP,HOLE_C10D3_5B10_OB22XC5_NPM_TEAR_SPD,,HOLE_C10D3_5B10_OB22XC5_NPM_TEAR_SPD,9055.12,472.44,270.000,NO
H19,HOLE_HOLE_C10-16D6-4B10_OB22XC5,HOLE_C10-16D6-4B10_OB22XC5B_NP,,HOLE_C10-16D6-4B10_OB22XC5B_NPB,12401.58,5212.60,270.000,NO
H20,HOLE_HOLE_C10-16D6-4B10_OB22XC5,HOLE_C10-16D6-4B10_OB22XC5B_NP,,HOLE_C10-16D6-4B10_OB22XC5B_NPB,12401.58,574.80,270.000,NO
H21,HOLE_N_HOLE_TOOLINGD125N_T2-0_I,HOLE_TOOLINGD125N_T2-0,,HOLE_TOOLINGD125N_T2-0,1750.00,1005.00,0.000,NO
H22,HOLE_N_HOLE_TOOLINGD125N_T2-0_I,HOLE_TOOLINGD125N_T2-0,,HOLE_TOOLINGD125N_T2-0,9644.60,169.50,0.000,NO
H23,HOLE_N_HOLE_TOOLINGD125N_T2-0_I,HOLE_TOOLINGD125N_T2-0,,HOLE_TOOLINGD125N_T2-0,8775.10,5586.20,0.000,NO
H24,HOLE_HOLE_C8D4-22B8I6-02_RO7-02,HOLE_C8D4-22B8I6-02_RO7-02_NPT_RB,,HOLE_C8D4-22B8I6-02_RO7-02_NPT_RB,12260.24,3994.29,0.000,NO
H25,HOLE_HOLE_C8D4-22B8I6-02_RO7-02,HOLE_C8D4-22B8I6-02_RO7-02_NPT_RB,,HOLE_C8D4-22B8I6-02_RO7-02_NPT_RB,12260.24,1744.29,0.000,NO
J1,CONN60_101062636003003LF_HSD_M6,CONN60_10106267-6003502LF,,HSD_M60D4H2D_P2-54W2-54_LDHXA,8325.59,1494.08,270.000,NO
J2,CONN48_101062676000402LF_HSD_M4,CONN48_10106267-6000402LF,,HSD_M48D4H2D_P2-54W2-54_LUV,2967.52,1596.85,90.000,NO
J5,CONN36_101062674001501LF_HSD_M3,CONN36_10106267-4001501LF,,HSD_M36D1H2D_P2-54,12260.24,2869.29,0.000,NO
J7,CONN32_10134214001616CLF_CON_M3,CONN32_10164834-002QLF,,CON_M32D4H2D_P1-27W1-27_RDVXA,337.80,3147.24,0.000,NO
J10,TDR_3P_TH2_TDR_3P_C85P67_141_10,TDR_3P_C85P67_141_100M_Q,,TDR_3P_C85P67_141_100M_Q,10960.17,6356.87,90.000,NO
J11,TDR_3P_TH2_TDR_3P_C85P67_141_10,TDR_3P_C85P67_141_100M_Q,,TDR_3P_C85P67_141_100M_Q,10960.17,6075.42,90.000,YES
J12,TDR_3P_TH2_TDR_3P_C85P67_141_10,TDR_3P_C85P67_141_100M_Q,,TDR_3P_C85P67_141_100M_Q,7533.14,6075.42,270.000,NO
J13,TDR_3P_TH2_TDR_3P_C85P67_141_10,TDR_3P_C85P67_141_100M_Q,,TDR_3P_C85P67_141_100M_Q,7534.20,6356.87,270.000,YES
J14,CONN1_10045597101LF_CON_GUIDE-F,CONN1_10045597-101LF,,CON_GUIDE-F1XF,827.95,4822.05,270.000,NO
J15,CONN1_10045597101LF_CON_GUIDE-F,CONN1_10045597-101LF,,CON_GUIDE-F1XF,827.95,997.24,270.000,NO
JP2,CONN3_10139134903ALF_HEADER1X3X,CONN3_HBB1037-L300D-8H,,HEADER1X3XL,10110.00,980.00,180.000,NO
JP3,CONN3_10139134903ALF_HEADER1X3X,CONN3_HBB1037-L300D-8H,,HEADER1X3XL,11510.00,904.00,90.000,NO
L1,L_L_MSE-12HZN1R0M-M1Q_DISCRETE_,1.5UH,,L_MSE-12HZN1R0M-M1Q,8639.17,4458.55,90.000,NO
L3,L_L_MSE-12HZN1R0M-M1Q_DISCRETE_,1.5UH,,L_MSE-12HZN1R0M-M1Q,8829.11,5130.70,180.000,NO
L5,L_L_MSE-12HZN1R0M-M1Q_DISCRETE_,1.5UH,,L_MSE-12HZN1R0M-M1Q,8073.15,4458.55,90.000,NO
ME1,ME_DUMMY_SYMBOL_PB-E1_SMALL_MEC,PB-E1_SMALL,,PB-E1_SMALL,3813.00,875.00,0.000,NO
ME2,ME_DUMMY_SYMBOL_WEEE_MECHANICAL,WEEE,,WEEE,3780.00,345.00,0.000,NO
ME3,ME_DUMMY_SYMBOL_QUANTA_LOGO_7X2,QUANTA_LOGO_7X26,,QUANTA_LOGO_7X26,1920.00,700.00,0.000,NO
ME4,ME_DUMMY_SYMBOL_SNLABEL_7X7_MEC,SNLABEL_7X7,,SNLABEL_7X7,3337.20,657.20,0.000,NO
ME5,ME_DUMMY_SYMBOL_PCB_VENDOR_LOGO,PCB_VENDOR_LOGO_15X8,,PCB_VENDOR_LOGO_15X8,5765.00,305.00,0.000,NO
PC1,CAP_NP_25V_C0402-0201_CH4104K1B,0.1UF,,C0402-0201,11140.00,1940.00,90.000,NO
PC2,CAP_NP_25V_C0402-0201_CH4104K1B,0.1UF,,C0402-0201,11390.00,2005.00,0.000,YES
PC3,CAP_NP_100V_C1206_H66_CH5108K12,1UF,,C1206_H66,10250.00,1370.00,270.000,NO
PC4,CAP_NP_16V_C0402-0201_CH5103KEB,1UF,,C0402-0201,10360.00,1395.00,0.000,YES
PC5,CAP_NP_25V_C0402-0201_CH4104K1B,0.1UF,,C0402-0201,10425.54,1432.67,0.000,NO
PC6,CAP_NP_50V_C0402-0201_CH21006JB,1000PF,,C0402-0201,10415.00,1875.00,90.000,NO
PC7,CAP_NP_50V_C0402-0201_CH22206KB,2200PF,,C0402-0201,10425.54,1392.67,180.000,NO
PC8,CAP_NP_100V_C0603_CH4108K1901_0,0.1UF,,C0603,10933.43,4144.43,90.000,YES
PC9,CAP_NP_25V_C0402-0201_CH4104K1B,0.1UF,,C0402-0201,11060.00,1940.00,90.000,NO
PC10,CAP_NP_25V_C0402-0201_CH5104KEB,1UF,,C0402-0201,11330.00,1940.00,90.000,NO
PC11,CAP_NP_25V_C0402-0201_CH4224K1B,0.22UF,,C0402-0201,10895.00,1710.00,0.000,YES
PC12,CAP_NP_25V_C0402-0201_CH2824K1B,8200PF,,C0402-0201,10895.00,1640.00,0.000,YES
PC13,CAP_NP_100V_C0805_H57_CH3478K1A,0.047UF,,C0805_H57,11480.85,1459.13,180.000,NO
PC15,CAPACITOR_POL_100V_EC5_10-5_21-,100UF,,EC5_10-5_21-5,5765.00,5390.00,90.000,NO
PC16,CAPACITOR_POL_100V_EC5_10-5_21-,100UF,,EC5_10-5_21-5,5285.00,5390.00,90.000,NO
PC17,CAPACITOR_POL_100V_EC5_10-5_21-,100UF,,EC5_10-5_21-5,4805.00,5390.00,90.000,NO
PC18,CAP_NP_100V_C1206_H76_DISCRETE_,2.2UF,,C1206_H76,5870.00,5125.00,0.000,NO
PC19,CAP_NP_100V_C1206_H76_DISCRETE_,2.2UF,,C1206_H76,5870.00,5035.00,0.000,NO
PC20,CAP_NP_100V_C1206_H76_DISCRETE_,2.2UF,,C1206_H76,5390.00,5035.00,0.000,NO
PC21,CAP_NP_100V_C1206_H76_DISCRETE_,2.2UF,,C1206_H76,5390.00,5125.00,0.000,NO
PC22,CAP_NP_100V_C1206_H76_DISCRETE_,2.2UF,,C1206_H76,4910.00,5125.00,0.000,NO
PC23,CAP_NP_100V_C1206_H76_DISCRETE_,2.2UF,,C1206_H76,4910.00,5035.00,0.000,NO
PC28,CAP_NP_25V_C0402_DISCRETE_CH410,0.1UF,,C0402,5475.00,2480.00,0.000,NO
PC29,CAP_NP_50V_C0402_DISCRETE_CH210,1000PF,,C0402,5475.00,2435.00,0.000,NO
PC30,CAP_NP_16V_C0805_H57_DISCRETE_C,22UF,,C0805_H57,6835.00,2040.00,0.000,NO
PC31,CAP_NP_16V_C0805_H57_DISCRETE_C,22UF,,C0805_H57,6835.00,1965.00,0.000,NO
PC32,CAP_NP_16V_C0805_H57_DISCRETE_C,22UF,,C0805_H57,6620.00,2040.00,0.000,NO
PC33,CAP_NP_16V_C0805_H57_DISCRETE_C,22UF,,C0805_H57,6620.00,1965.00,0.000,NO
PC34,CAP_NP_16V_C0805_H57_DISCRETE_C,22UF,,C0805_H57,6405.00,2040.00,0.000,NO
PC35,CAP_NP_16V_C0805_H57_DISCRETE_C,22UF,,C0805_H57,6405.00,1965.00,0.000,NO
PC36,CAP_NP_16V_C0805_H57_DISCRETE_C,22UF,,C0805_H57,6190.00,1965.00,0.000,NO
PC37,CAP_NP_16V_C0805_H57_DISCRETE_C,22UF,,C0805_H57,6190.00,2040.00,0.000,NO
PC38,CAP_NP_16V_C0805_H57_DISCRETE_C,22UF,,C0805_H57,5975.00,2040.00,0.000,NO
PC39,CAP_NP_16V_C0805_H57_DISCRETE_C,22UF,,C0805_H57,5975.00,1965.00,0.000,NO
PC40,CAPACITOR_POL_16V_EC5_10-5_21-5,2200UF,,EC5_10-5_21-5XA,5785.00,2400.00,0.000,NO
PC41,CAPACITOR_POL_16V_EC5_10-5_21-5,2200UF,,EC5_10-5_21-5XA,6665.00,2400.00,0.000,NO
PC42,CAPACITOR_POL_16V_EC5_10-5_21-5,2200UF,,EC5_10-5_21-5XA,6225.00,2400.00,0.000,NO
PC43,CAPACITOR_POL_100V_EC5_10-5_21-,100UF,,EC5_10-5_21-5,4190.19,5390.00,90.000,NO
PC44,CAPACITOR_POL_100V_EC5_10-5_21-,100UF,,EC5_10-5_21-5,3710.19,5390.00,90.000,NO
PC45,CAPACITOR_POL_100V_EC5_10-5_21-,100UF,,EC5_10-5_21-5,3230.19,5390.00,90.000,NO
PC46,CAP_NP_100V_C1206_H76_DISCRETE_,2.2UF,,C1206_H76,4295.19,5035.00,0.000,NO
PC47,CAP_NP_100V_C1206_H76_DISCRETE_,2.2UF,,C1206_H76,4295.19,5125.00,0.000,NO
PC48,CAP_NP_100V_C1206_H76_DISCRETE_,2.2UF,,C1206_H76,3815.19,5125.00,0.000,NO
PC49,CAP_NP_100V_C1206_H76_DISCRETE_,2.2UF,,C1206_H76,3815.19,5035.00,0.000,NO
PC50,CAP_NP_100V_C1206_H76_DISCRETE_,2.2UF,,C1206_H76,3335.19,5035.00,0.000,NO
PC51,CAP_NP_100V_C1206_H76_DISCRETE_,2.2UF,,C1206_H76,3335.19,5125.00,0.000,NO
PC56,CAP_NP_25V_C0402_DISCRETE_CH410,0.1UF,,C0402,3940.00,2470.00,0.000,NO
PC57,CAP_NP_50V_C0402_DISCRETE_CH210,1000PF,,C0402,3940.00,2425.00,0.000,NO
PC64,CAP_NP_16V_C0805_H57_DISCRETE_C,22UF,,C0805_H57,4190.00,2045.00,0.000,NO
PC65,CAP_NP_16V_C0805_H57_DISCRETE_C,22UF,,C0805_H57,4190.00,1970.00,0.000,NO
PC66,CAP_NP_16V_C0805_H57_DISCRETE_C,22UF,,C0805_H57,3975.00,2045.00,0.000,NO
PC67,CAP_NP_16V_C0805_H57_DISCRETE_C,22UF,,C0805_H57,3975.00,1970.00,0.000,NO
PC68,CAPACITOR_POL_16V_EC5_10-5_21-5,2200UF,,EC5_10-5_21-5XA,4285.00,2400.00,0.000,NO
PC69,CAPACITOR_POL_16V_EC5_10-5_21-5,2200UF,,EC5_10-5_21-5XA,5165.00,2400.00,0.000,NO
PC70,CAPACITOR_POL_16V_EC5_10-5_21-5,2200UF,,EC5_10-5_21-5XA,4725.00,2400.00,0.000,NO
PC71,CAPACITOR_POL_100V_EC5_10-5_21-,100UF,,EC5_10-5_21-5,2615.39,5390.00,90.000,NO
PC72,CAPACITOR_POL_100V_EC5_10-5_21-,100UF,,EC5_10-5_21-5,2135.39,5390.00,90.000,NO
PC73,CAPACITOR_POL_100V_EC5_10-5_21-,100UF,,EC5_10-5_21-5,1655.39,5390.00,90.000,NO
PC74,CAP_NP_100V_C1206_H76_DISCRETE_,2.2UF,,C1206_H76,1760.39,5035.00,0.000,NO
PC75,CAP_NP_100V_C1206_H76_DISCRETE_,2.2UF,,C1206_H76,1760.39,5125.00,0.000,NO
PC76,CAP_NP_100V_C1206_H76_DISCRETE_,2.2UF,,C1206_H76,2240.39,5125.00,0.000,NO
PC77,CAP_NP_100V_C1206_H76_DISCRETE_,2.2UF,,C1206_H76,2240.39,5035.00,0.000,NO
PC78,CAP_NP_100V_C1206_H76_DISCRETE_,2.2UF,,C1206_H76,2720.39,5035.00,0.000,NO
PC79,CAP_NP_100V_C1206_H76_DISCRETE_,2.2UF,,C1206_H76,2720.39,5125.00,0.000,NO
PC82,CAP_NP_100V_C0603_CH3338K1900_0,0.033UF,,C0603,10833.43,3999.43,0.000,YES
PC83,CAP_NP_16V_C0603_CH4683K1901_0.,0.68UF,,C0603,10420.00,1265.00,180.000,NO
PC84,CAP_NP_25V_C0402_DISCRETE_CH410,0.1UF,,C0402,2380.00,2475.00,0.000,NO
PC85,CAP_NP_50V_C0402_DISCRETE_CH210,1000PF,,C0402,2380.00,2430.00,0.000,NO
PC86,CAP_NP_16V_C0805_H57_DISCRETE_C,22UF,,C0805_H57,3760.00,2045.00,0.000,NO
PC87,CAP_NP_16V_C0805_H57_DISCRETE_C,22UF,,C0805_H57,3760.00,1970.00,0.000,NO
PC88,CAP_NP_16V_C0805_H57_DISCRETE_C,22UF,,C0805_H57,3545.00,2045.00,0.000,NO
PC89,CAP_NP_16V_C0805_H57_DISCRETE_C,22UF,,C0805_H57,3545.00,1965.00,0.000,NO
PC90,CAP_NP_16V_C0805_H57_DISCRETE_C,22UF,,C0805_H57,3330.00,2045.00,0.000,NO
PC91,CAP_NP_16V_C0805_H57_DISCRETE_C,22UF,,C0805_H57,3330.00,1965.00,0.000,NO
PC92,CAP_NP_16V_C0805_H57_DISCRETE_C,22UF,,C0805_H57,3115.00,2045.00,0.000,NO
PC93,CAP_NP_16V_C0805_H57_DISCRETE_C,22UF,,C0805_H57,3115.00,1965.00,0.000,NO
PC94,CAP_NP_16V_C0805_H57_DISCRETE_C,22UF,,C0805_H57,2900.00,2045.00,0.000,NO
PC95,CAP_NP_16V_C0805_H57_DISCRETE_C,22UF,,C0805_H57,2900.00,1965.00,0.000,NO
PC96,CAPACITOR_POL_16V_EC5_10-5_21-5,2200UF,,EC5_10-5_21-5XA,3570.00,2400.00,0.000,NO
PC97,CAPACITOR_POL_16V_EC5_10-5_21-5,2200UF,,EC5_10-5_21-5XA,3125.00,2400.00,0.000,NO
PC98,CAPACITOR_POL_16V_EC5_10-5_21-5,2200UF,,EC5_10-5_21-5XA,2680.00,2400.00,0.000,NO
PC99,CAP_NP_50V_C0402_DISCRETE_CH410,100NF,,C0402,6440.00,370.00,0.000,NO
PC100,CAP_NP_16V_C0805_H57_DISCRETE_C,22UF,,C0805_H57,6853.00,492.00,90.000,NO
PC101,CAP_NP_16V_C0805_H57_DISCRETE_C,22UF,,C0805_H57,6774.00,492.00,90.000,NO
PC102,CAP_NP_50V_C0402_DISCRETE_CH410,100NF,,C0402,6914.00,493.00,90.000,NO
PC103,CAP_NP_25V_C0402-0201_DISCRETE_,0.22UF,,C0402-0201,7100.00,480.00,270.000,NO
PC104,CAP_NP_50V_C0402-0201_DISCRET_1,100NF,,C0402-0201,7545.00,275.00,0.000,NO
PC105,CAP_NP_6.3V_C0805_H61_DISCRETE_,22UF,,C0805_H61,7545.00,345.00,0.000,NO
PC106,CAP_NP_6.3V_C0805_H61_DISCRETE_,22UF,,C0805_H61,7545.00,430.00,0.000,NO
PC107,CAP_NP_6.3V_C0805_H61_DISCRETE_,22UF,,C0805_H61,7545.00,515.00,0.000,NO
PC108,CAP_NP_6.3V_C0805_H61_DISCRETE_,22UF,,C0805_H61,7545.00,600.00,0.000,NO
PC109,CAP_NP_25V_C0402-0201_DISCRET_1,1UF,,C0402-0201,7001.00,578.00,180.000,NO
PC110,CAP_NP_50V_C0402-0201_DISCRET_2,3300PF,,C0402-0201,7030.35,366.95,0.000,NO
PC111,CAP_NP_50V_C0402-0201_DISCRET_3,100PF,,C0402-0201,6960.00,270.00,0.000,NO
PC112,CAP_NP_25V_C0402-0201_CH4224K1B,0.22UF,,C0402-0201,7545.00,685.00,0.000,NO
PC113,CAPACITOR_POL_100V_EC5_10-5_21-,100UF,,EC5_10-5_21-5,7339.81,5390.00,90.000,NO
PC114,CAPACITOR_POL_100V_EC5_10-5_21-,100UF,,EC5_10-5_21-5,6859.81,5390.00,90.000,NO
PC115,CAPACITOR_POL_100V_EC5_10-5_21-,100UF,,EC5_10-5_21-5,6379.81,5390.00,90.000,NO
PC116,CAP_NP_100V_C1206_H76_DISCRETE_,2.2UF,,C1206_H76,7444.81,5125.00,0.000,NO
PC117,CAP_NP_100V_C1206_H76_DISCRETE_,2.2UF,,C1206_H76,6964.81,5125.00,0.000,NO
PC118,CAP_NP_100V_C1206_H76_DISCRETE_,2.2UF,,C1206_H76,6964.81,5035.00,0.000,NO
PC119,CAP_NP_100V_C1206_H76_DISCRETE_,2.2UF,,C1206_H76,7444.81,5035.00,0.000,NO
PC120,CAP_NP_100V_C1206_H76_DISCRETE_,2.2UF,,C1206_H76,6484.81,5125.00,0.000,NO
PC121,CAP_NP_100V_C1206_H76_DISCRETE_,2.2UF,,C1206_H76,6484.81,5035.00,0.000,NO
PC122,CAP_NP_25V_C0402_DISCRETE_CH410,0.1UF,,C0402,7049.81,2480.00,0.000,NO
PC123,CAP_NP_50V_C0402_DISCRETE_CH210,1000PF,,C0402,7049.81,2435.00,0.000,NO
PC127,CAP_NP_16V_C0805_H57_DISCRETE_C,22UF,,C0805_H57,7049.90,2040.00,0.000,NO
PC128,CAP_NP_16V_C0805_H57_DISCRETE_C,22UF,,C0805_H57,7264.90,2040.00,0.000,NO
PC132,CAP_NP_16V_C0805_H57_DISCRETE_C,22UF,,C0805_H57,7049.90,1965.00,0.000,NO
PC133,CAP_NP_16V_C0805_H57_DISCRETE_C,22UF,,C0805_H57,7264.90,1965.00,0.000,NO
PC134,CAPACITOR_POL_16V_EC5_10-5_21-5,2200UF,,EC5_10-5_21-5XA,8239.81,2400.00,0.000,NO
PC135,CAPACITOR_POL_16V_EC5_10-5_21-5,2200UF,,EC5_10-5_21-5XA,7799.81,2400.00,0.000,NO
PC136,CAPACITOR_POL_16V_EC5_10-5_21-5,2200UF,,EC5_10-5_21-5XA,7359.81,2400.00,0.000,NO
PC487,CAP_NP_6.3V_C1206_H76_CH6471ME2,47UF,,C1206_H76,10685.54,1332.67,270.000,NO
PC551,CAP_NP_16V_C0402-0201_CH3563K1B,0.056UF,,C0402-0201,10425.54,1352.67,180.000,NO
PC553,CAP_NP_50V_C0603_DISCRETE_CH422,0.22UF,,C0603,10833.43,3925.00,0.000,YES
PC557,CAP_NP_25V_C0402-0201_CH4104K1B,0.1UF,,C0402-0201,11220.00,1940.00,90.000,NO
PC558,CAP_NP_100V_C1206_H42_CH4108K12,0.1UF,,C1206_H42,11406.41,1995.99,90.000,NO
PC559,CAP_NP_100V_C1206_H66_DISCRETE_,1UF,,C1206_H66,11612.00,1660.00,270.000,NO
PC560,CAP_NP_50V_C0402-0201_DISCRET_4,1000PF,,C0402-0201,11274.93,1927.56,0.000,NO
PC561,CAP_NP_50V_C0402-0201_CH31006KB,0.01UF,,C0402-0201,10979.68,1835.99,180.000,NO
PC562,CAP_NP_25V_C0603_DISCRETE_CH510,1UF,,C0603,10985.00,1685.00,180.000,NO
PC563,CAP_NP_100V_C0603_CH4108K1901_0,0.1UF,,C0603,10933.43,3669.43,90.000,YES
PC564,CAP_NP_100V_C0603_CH3338K1900_0,0.033UF,,C0603,10833.43,3524.43,0.000,YES
PC565,CAP_NP_50V_C0603_DISCRETE_CH422,0.22UF,,C0603,10833.43,3439.43,0.000,YES
PC566,CAP_NP_16V_C0805_H57_DISCRETE_C,22UF,,C0805_H57,6695.00,492.00,90.000,NO
PC567,CAP_NP_16V_C0805_H57_DISCRETE_C,22UF,,C0805_H57,6616.00,492.00,90.000,NO
PC568,CAP_NP_16V_C0805_H57_DISCRETE_C,22UF,,C0805_H57,6537.00,492.00,90.000,NO
PD6,SCHOTTKY_AC_D2723_SMCXC_IC_BC0M,60V/51.70A,,D2723_SMCXC,11835.61,1434.59,270.000,YES
PD7,SCHOTTKY_AC_D2723_SMCXC_IC_BC0M,60V/51.70A,,D2723_SMCXC,11835.61,1434.59,90.000,NO
PD8,SCHOTTKY_AC_D2723_SMCXD_IC _BC0,B380-13-F,,D2723_SMCXD,10910.00,5455.00,180.000,NO
PD14,DIODE_SOD323_IC_BC004448Z64_1N4,1N4448WS-7-F,,SOD323,10863.43,3639.43,270.000,YES
PD15,DIODE_SOD323_IC_BC004448Z64_1N4,1N4448WS-7-F,,SOD323,10863.43,4114.43,270.000,YES
PJ1,JUMPER-2_1_SHORT_R0603_IO_SHORT,SHORT,,SHORT_R0603,11485.85,1249.13,0.000,NO
PL1,L_L0603_DISCRETE_CX220TN1001_BL,BLM18SN220TN1D,,L0603,6442.00,452.00,0.000,NO
PL2,L_L_PCMC063T_DISCRETE_CV-4755MZ,4.7U,,L_PCMC063T,7295.00,510.00,0.000,NO
PQ1,BUZ80A_1_SOT404_GDSXA_IC_BAMN3R,PSMN3R7-100BSE,,SOT404_GDSXA,11039.20,4979.42,0.000,NO
PQ2,BUZ80A_1_SOT404_GDSXA_IC_BAMN3R,PSMN3R7-100BSE,,SOT404_GDSXA,11039.20,4504.42,0.000,NO
PQ3,BUZ80A_1_SOT404_GDSXA_IC_BAMN3R,PSMN3R7-100BSE,,SOT404_GDSXA,11039.20,4029.42,0.000,NO
PQ4,BUZ80A_1_SOT404_GDSXA_IC_BAMN3R,PSMN3R7-100BSE,,SOT404_GDSXA,11039.20,3554.42,0.000,NO
PQ5,BUZ80A_1_SOT404_GDSXA_IC_BAMN3R,PSMN3R7-100BSE,,SOT404_GDSXA,11039.20,3079.42,0.000,NO
PQ6,BUZ80A_1_SOT404_GDSXA_IC_BAMN3R,PSMN3R7-100BSE,,SOT404_GDSXA,11039.20,2604.42,0.000,NO
PQ15,NPN_0_SOT23_BEC_IC_BA0390400H0_,MMBT3904-7-F,,SOT23_BEC,11259.68,2280.60,0.000,NO
PR1,Q_SP_RES4P_R2725_4P_DISCRETE_SP,0.0003,,R2725_4P,11797.40,4504.42,180.000,NO
PR2,R_R0805_H26_DISCRETE_CS39534FA0,95.3K,,R0805_H26,11480.00,2100.00,90.000,YES
PR3,R_R0805_H26_DISCRETE_CS39534FA0,95.3K,,R0805_H26,11405.00,2100.00,90.000,YES
PR4,R_R0805_H26_DISCRETE_CS39534FA0,95.3K,,R0805_H26,11555.00,2100.00,90.000,YES
PR5,R_R1206XN_DISCRETE_CS11007J200_,100,,R1206XN,11550.00,1995.00,270.000,NO
PR8,R_R0603_H24_DISCRETE_CS01003F90,10,,R0603_H24,10645.00,5108.42,270.000,NO
PR9,R_R0402-0201_DISCRETE_CS21652FB,1.65K,,R0402-0201,11100.00,1940.00,90.000,NO
PR10,R_R0402-0201_DISCRETE_CS22212FB,2.21K,,R0402-0201,11390.00,1965.00,0.000,YES
PR11,R_R0402-0201_DISCRETE_CS00002JB,0,,R0402-0201,10590.00,1420.00,180.000,YES
PR12,R_R0603_H24_DISCRETE_CS01003F90,10,,R0603_H24,10645.00,4633.42,270.000,NO
PR13,R_R0603_H24_DISCRETE_CS01003F90,10,,R0603_H24,10645.00,4158.42,270.000,NO
PR14,R_R0603_H24_DISCRETE_CS01003F90,10,,R0603_H24,10645.00,3625.42,90.000,NO
PR15,R_R0603_H24_DISCRETE_CS01003F90,10,,R0603_H24,10645.00,3208.42,270.000,NO
PR16,R_R0603_H24_DISCRETE_CS01003F90,10,,R0603_H24,10645.00,2733.42,270.000,NO
PR17,R_R0805_H26_DISCRETE_CS39534FA0,95.3K,,R0805_H26,11329.41,1282.56,90.000,NO
PR18,R_R0805_H26_DISCRETE_CS52054FA0,2.05M,,R0805_H26,11240.00,2145.00,0.000,YES
PR19,R_R0805_H26_DISCRETE_CS52054FA0,2.05M,,R0805_H26,10950.00,1995.00,0.000,NO
PR20,R_R0402-0201_DISCRETE_CS21002FB,1K,,R0402-0201,10945.00,1735.00,180.000,NO
PR21,R_R0402-0201_DISCRETE_CS34872FB,48.7K,,R0402-0201,10980.00,1880.00,180.000,NO
PR23,R_R0805_DISCRETE_CS41744FA00_1/,174K,,R0805,10245.54,1992.67,0.000,NO
PR24,R_R0402-0201_DISCRETE_CS31202FB,12K,,R0402-0201,10401.00,1937.00,0.000,NO
PR25,R_R0805_H26_DISCRETE_CS44994FA0,499K,,R0805_H26,10245.54,1887.67,0.000,NO
PR26,R_R0402_DISCRETE_CS33302FB00_1/,33K,,R0402,10940.00,4015.00,0.000,YES
PR27,R_R0402-0201_DISCRETE_CS31302FB,13K,,R0402-0201,10480.00,1290.00,180.000,YES
PR28,R_R0402-0201_DISCRETE_CS37502FB,75K,,R0402-0201,10615.00,1340.00,0.000,YES
PR31,R_R0402-0201_DISCRETE_CS31692FB,16.9K,,R0402-0201,11020.00,1650.00,0.000,YES
PR32,R_R0805_H26_DISCRETE_CS32004FA0,20K,,R0805_H26,11525.87,1354.18,90.000,NO
PR33,R_R0402-0201_DISCRETE_CS00002JB,0,,R0402-0201,10495.54,1312.67,180.000,NO
PR35,R_R0402-0201_DISCRETE_CS41002FB,100K,,R0402-0201,11045.00,1405.00,270.000,NO
PR36,R_R0402-0201_DISCRETE_CS43302FB,330K,,R0402-0201,10895.00,1745.00,0.000,YES
PR37,R_R0402-0201_DISCRETE_CS43902FB,390K,,R0402-0201,10895.00,1675.00,0.000,YES
PR50,R_R0402_DISCRETE_CS00002JB13_1/,0,,R0402,5624.02,3020.00,270.000,YES
PR52,R_R0402-0201_DISCRETE_CS00002JB,0,,R0402-0201,5230.32,3020.00,270.000,YES
PR58,R_R0402-0201_DISCRETE_CS41072FB,107K,,R0402-0201,5545.28,3020.00,90.000,YES
PR59,R_R0805_H26_DISCRETE_CS23304FA0,3.3K,,R0805_H26,5475.00,2375.00,0.000,NO
PR65,R_R0402_DISCRETE_CS00002JB13_1/,0,,R0402,4048.21,3020.00,270.000,YES
PR67,R_R0402-0201_DISCRETE_CS00002JB,0,,R0402-0201,3655.51,3020.00,270.000,YES
PR73,R_R0402-0201_DISCRETE_CS38872FB,88.7K,,R0402-0201,3970.47,3020.00,90.000,YES
PR74,R_R0805_H26_DISCRETE_CS23304FA0,3.3K,,R0805_H26,3940.00,2365.00,0.000,NO
PR78,R_R0402_DISCRETE_CS00002JB13_1/,0,,R0402,2474.41,3020.00,270.000,YES
PR79,R_R0402-0201_DISCRETE_CS00002JB,0,,R0402-0201,2080.71,3020.00,270.000,YES
PR86,R_R0805_H26_DISCRETE_CS23304FA0,3.3K,,R0805_H26,2380.00,2370.00,0.000,NO
PR87,R_R0402-0201_DISCRETE_CS31002JB,10K,,R0402-0201,7030.00,320.00,0.000,NO
PR88,R_R0402-0201_DISCRETE_CS36042FB,60.4K,,R0402-0201,7060.00,580.00,90.000,NO
PR89,R_R0402-0201_DISCRETE_CS31052FB,10.5K,,R0402-0201,6885.00,365.00,180.000,NO
PR90,R_R0402-0201_DISCRETE_CS35602FB,56K,,R0402-0201,6960.00,320.00,0.000,NO
PR91,R_R0402-0201_DISCRETE_CS31242FB,12.4K,,R0402-0201,6960.35,366.95,0.000,NO
PR92,R_R0402-0201_DISCRETE_CS00002JB,0,,R0402-0201,10210.00,980.00,180.000,NO
PR93,R_R0402-0201_DISCRETE_CS31002FB,10K,,R0402-0201,11020.00,1685.00,0.000,YES
PR209,R_R0402-0201_DISCRETE_CS00002JB,0,,R0402-0201,10670.00,1875.00,270.000,NO
PR210,R_R0402-0201_DISCRETE_CS00002JB,0,,R0402-0201,10480.00,1370.00,270.000,NO
PR211,R_R0402-0201_DISCRETE_CS51002FB,1M,,R0402-0201,10425.54,1312.67,180.000,NO
PR212,R_R0402-0201_DISCRETE_CS31002FB,10K,,R0402-0201,10480.00,1255.00,0.000,YES
PR213,R_R0402-0201_DISCRETE_CS31002FB,10K,,R0402-0201,10615.00,1305.00,0.000,YES
PR214,R_R0402-0201_DISCRETE_CS31002FB,10K,,R0402-0201,10480.00,1336.00,0.000,YES
PR220,R_R0603_H24_DISCRETE_CS11003J90,100,,R0603_H24,10910.00,3945.00,90.000,YES
PR313,R_R0402-0201_DISCRETE_CS03302FB,33,,R0402-0201,10210.00,1180.00,180.000,NO
PR314,R_R0402-0201_DISCRETE_CS-2202FB,2.2,,R0402-0201,7100.00,405.00,90.000,NO
PR315,Q_SP_RES4P_R2725_4P_DISCRETE_SP,0.0003,,R2725_4P,11796.51,3079.42,180.000,NO
PR318,R_R0402_DISCRETE_CS00002JB13_1/,0,,R0402,7198.83,3020.00,270.000,YES
PR319,R_R0402-0201_DISCRETE_CS00002JB,0,,R0402-0201,6805.13,3020.00,270.000,YES
PR320,R_R0402-0201_DISCRETE_CS36982FB,69.8K,,R0402-0201,7120.09,3020.00,90.000,YES
PR321,R_R0805_H26_DISCRETE_CS23304FA0,3.3K,,R0805_H26,7049.81,2375.00,0.000,NO
PR322,R_R0402-0201_DISCRETE_CS00002JB,0,,R0402-0201,2515.00,3020.00,270.000,YES
PR323,R_R0402-0201_DISCRETE_CS00002JB,0,,R0402-0201,7240.00,3020.00,270.000,YES
PR324,R_R0402-0201_DISCRETE_CS00002JB,0,,R0402-0201,4090.00,3020.00,90.000,YES
PR325,R_R0402-0201_DISCRETE_CS35622FB,56.2K,,R0402-0201,2395.67,3020.00,270.000,YES
PR5864,R_R0402-0201_DISCRETE_CS12002FB,200,,R0402-0201,11794.11,3467.50,180.000,NO
PR6931,R_R0402-0201_DISCRETE_CS22262FB,2.26K,,R0402-0201,11180.00,1940.00,90.000,NO
PR6932,R_R0402-0201_DISCRETE_CS22432FB,2.43K,,R0402-0201,11317.00,1384.57,0.000,NO
PR6933,R_R0402-0201_DISCRETE_CS34322FB,43.2K,,R0402-0201,10980.00,1795.00,180.000,NO
PR6934,R_R0402-0201_DISCRETE_CS41002FB,100K,,R0402-0201,11020.00,1735.00,0.000,NO
PR6935,R_R0402-0201_DISCRETE_CS37152FB,71.5K,,R0402-0201,11281.68,1425.56,0.000,NO
PR6954,R_R0603_H24_DISCRETE_CS01003F90,10,,R0603_H24,11714.11,3417.50,180.000,NO
PR6955,R_R0603_H24_DISCRETE_CS-1003F90,1,,R0603_H24,11874.11,3417.50,0.000,NO
PR6956,R_R0603_H24_DISCRETE_CS-1003F90,1,,R0603_H24,11875.00,4842.50,0.000,NO
PR6957,R_R0603_H24_DISCRETE_CS01003F90,10,,R0603_H24,11715.00,4842.50,180.000,NO
PR6958,R_R0603_H24_DISCRETE_CS01003F90,10,,R0603_H24,11715.00,4712.50,180.000,NO
PR6959,R_R0603_H24_DISCRETE_CS01003F90,10,,R0603_H24,11714.11,3287.50,180.000,NO
PR6960,R_R0603_H24_DISCRETE_CS01003F90,10,,R0603_H24,11875.00,4712.50,0.000,NO
PR6961,R_R0603_H24_DISCRETE_CS01003F90,10,,R0603_H24,11874.11,3287.50,0.000,NO
PR6962,R_R0603_H24_DISCRETE_CS01003F90,10,,R0603_H24,11715.00,4782.50,180.000,NO
PR6963,R_R0603_H24_DISCRETE_CS-1003F90,1,,R0603_H24,11875.00,4782.50,0.000,NO
PR6964,R_R0603_H24_DISCRETE_CS-1003F90,1,,R0603_H24,11874.11,3357.50,180.000,NO
PR6965,R_R0603_H24_DISCRETE_CS01003F90,10,,R0603_H24,11714.11,3357.50,0.000,NO
PR6966,R_R0402_DISCRETE_CS11002FB07_1/,100,,R0402,11100.81,2317.41,0.000,NO
PR6967,R_R0402_DISCRETE_CS00002JB13_1/,0,,R0402,11132.31,2317.41,180.000,NO
PR6968,R_R0402_DISCRETE_CS00002JB13_1/,0,,R0402,11133.15,2242.41,180.000,NO
PR6969,R_R0402_DISCRETE_CS00002JB13_1/,0,,R0402,11101.65,2242.41,180.000,NO
PR6970,R_R0402_DISCRETE_CS33302FB00_1/,33K,,R0402,10940.00,3540.00,0.000,YES
PR6971,R_R0603_H24_DISCRETE_CS11003J90,100,,R0603_H24,10920.00,3469.00,90.000,YES
PR6972,R_R0402-0201_DISCRETE_CS12002FB,200,,R0402-0201,11795.00,4892.50,180.000,NO
PR6973,R_R0402-0201_DISCRETE_CS00002JB,0,,R0402-0201,10880.00,1030.00,0.000,NO
PU1,LTC4286HUKTRPBF_QFN39_TH_0-5_7X,LTC4287AUK#TRPBF,,QFN39_TH_0-5_7X7,10385.54,1627.67,0.000,NO
PU2,MODULE14P_Q50SN120A1NKDSF_MODUL,MODULE14P_Q50SN120A1NKDSF,,MODULE14P_Q50SN120A1NKDSF,5687.80,4772.04,0.000,NO
PU3,MODULE14P_Q50SN120A1NKDSF_MODUL,MODULE14P_Q50SN120A1NKDSF,,MODULE14P_Q50SN120A1NKDSF,4112.99,4772.04,0.000,NO
PU4,MODULE14P_Q50SN120A1NKDSF_MODUL,MODULE14P_Q50SN120A1NKDSF,,MODULE14P_Q50SN120A1NKDSF,2538.19,4772.04,0.000,NO
PU5,MPQ8626GDZ_QFN14_0-5_3X2XA_IC_A,MPQ8626GD-Z,,QFN14_0-5_3X2XA,7000.00,473.00,0.000,NO
PU6,MODULE14P_Q50SN120A1NKDSF_MODUL,MODULE14P_Q50SN120A1NKDSF,,MODULE14P_Q50SN120A1NKDSF,7262.61,4772.04,0.000,NO
PU7,ADM12721ACPZRL_LFCSP48_7X8_IC _,ADM1272-1ACPZ-RL,,LFCSP48_7X8,11320.68,1666.99,0.000,NO
R1,R_R0402-0201_DISCRETE_CS24702JB,4.7K,,R0402-0201,9396.96,3523.85,180.000,YES
R2,R_R0402-0201_DISCRETE_CS24702JB,4.7K,,R0402-0201,9391.96,3108.85,180.000,YES
R3,R_R0402-0201_DISCRETE_CS00002JB,0,,R0402-0201,9331.96,3493.85,90.000,YES
R4,R_R0402-0201_DISCRETE_CS03302FB,33,,R0402-0201,9380.00,3595.00,270.000,YES
R5,R_R0402-0201_DISCRETE_CS03302FB,33,,R0402-0201,9390.00,3065.00,180.000,YES
R6,R_R0402-0201_DISCRETE_CS00002JB,0,,R0402-0201,9396.96,3478.85,0.000,YES
R7,R_R0402-0201_DISCRETE_CS00002JB,0,,R0402-0201,9391.96,3153.85,0.000,YES
R17,R_R0402-0201_DISCRETE_CS24702JB,4.7K,,R0402-0201,8115.00,3250.00,90.000,YES
R18,R_R0402-0201_DISCRETE_CS21002FB,1K,,R0402-0201,8260.00,2745.00,270.000,YES
R19,R_R0402-0201_DISCRETE_CS21002FB,1K,,R0402-0201,8155.00,3250.00,90.000,YES
R20,R_R0402-0201_DISCRETE_CS21002FB,1K,,R0402-0201,8235.00,3250.00,90.000,YES
R21,R_R0402-0201_DISCRETE_CS21002FB,1K,,R0402-0201,8260.00,2645.00,90.000,YES
R22,R_R0402-0201_DISCRETE_CS21002FB,1K,,R0402-0201,8195.00,3250.00,270.000,YES
R23,R_R0402-0201_DISCRETE_CS21002FB,1K,,R0402-0201,8275.00,3250.00,270.000,YES
R24,R_R0402-0201_DISCRETE_CS24702JB,4.7K,,R0402-0201,9045.00,2960.00,90.000,YES
R27,R_R0402-0201_DISCRETE_CS00002JB,0,,R0402-0201,9035.00,3240.00,270.000,YES
R28,R_R0402-0201_DISCRETE_CS31002JB,10K,,R0402-0201,8360.00,3280.00,0.000,YES
R29,R_R0402-0201_DISCRETE_CS31002JB,10K,,R0402-0201,8270.00,3565.00,90.000,YES
R30,R_R0402-0201_DISCRETE_CS00002JB,0,,R0402-0201,8215.00,3565.00,270.000,YES
R32,R_R0402-0201_DISCRETE_CS00002JB,0,,R0402-0201,8430.00,3585.00,270.000,YES
R33,R_R0402-0201_DISCRETE_CS41002JB,100K,,R0402-0201,8475.00,3585.00,90.000,YES
R34,R_R0402-0201_DISCRETE_CS31002JB,10K,,R0402-0201,9200.00,3595.00,270.000,YES
R35,R_R0402-0201_DISCRETE_CS12002FB,200,,R0402-0201,9155.00,3595.00,270.000,YES
R36,R_R0402-0201_DISCRETE_CS21002FB,1K,,R0402-0201,8740.00,3545.00,90.000,YES
R37,R_R0402-0201_DISCRETE_CS31002JB,10K,,R0402-0201,8780.00,3545.00,270.000,YES
R38,R_R0402-0201_DISCRETE_CS24702JB,4.7K,,R0402-0201,8700.00,3085.00,270.000,YES
R39,R_R0402-0201_DISCRETE_CS24702JB,4.7K,,R0402-0201,8750.00,3085.00,270.000,YES
R40,R_R0402-0201_DISCRETE_CS24702JB,4.7K,,R0402-0201,8800.00,3085.00,270.000,YES
R41,R_R0402-0201_DISCRETE_CS03302FB,33,,R0402-0201,8645.00,3545.00,270.000,YES
R42,R_R0402-0201_DISCRETE_CS03302FB,33,,R0402-0201,8690.00,3545.00,270.000,YES
R43,R_R0402-0201_DISCRETE_CS12202JB,220,,R0402-0201,8700.00,2955.00,270.000,YES
R44,R_R0402-0201_DISCRETE_CS12202JB,220,,R0402-0201,8750.00,2955.00,270.000,YES
R45,R_R0402-0201_DISCRETE_CS12202JB,220,,R0402-0201,8800.00,2955.00,270.000,YES
R55,R_R1206XN_DISCRETE_CS21006J202_,1K,,R1206XN,8400.00,3760.00,270.000,NO
R56,R_R0402-0201_DISCRETE_CS13162FB,316,,R0402-0201,7823.54,2636.09,90.000,NO
R57,R_R1206XN_DISCRETE_CS21006J202_,1K,,R1206XN,8265.00,3686.00,180.000,NO
R58,R_R0402-0201_DISCRETE_CS13162FB,316,,R0402-0201,7873.54,2636.09,270.000,NO
R59,R_R0402-0201_DISCRETE_CS07502FB,75,,R0402-0201,8035.00,2635.00,90.000,NO
R60,R_R1206XN_DISCRETE_CS21006J202_,1K,,R1206XN,8265.00,3606.00,0.000,NO
R61,R_R0402-0201_DISCRETE_CS13162FB,316,,R0402-0201,7923.54,2636.09,90.000,NO
R62,R_R1206XN_DISCRETE_CS21006J202_,1K,,R1206XN,8265.00,3455.00,180.000,NO
R63,R_R1206XN_DISCRETE_CS21006J202_,1K,,R1206XN,8265.00,3375.00,0.000,NO
R65,R_R0402-0201_DISCRETE_CS03302FB,33,,R0402-0201,9470.00,2795.00,270.000,YES
R67,R_R0402-0201_DISCRETE_CS03302FB,33,,R0402-0201,9400.00,2795.00,270.000,YES
R69,R_R0402-0201_DISCRETE_CS13012FB,301,,R0402-0201,9330.00,2795.00,90.000,YES
R70,R_R0402-0201_DISCRETE_CS03302FB,33,,R0402-0201,9090.00,2795.00,270.000,YES
R71,R_R0402-0201_DISCRETE_CS11002FB,100,,R0402-0201,8880.00,2795.00,270.000,YES
R74,R_R0402-0201_DISCRETE_CS24702JB,4.7K,,R0402-0201,9470.00,2985.00,90.000,YES
R75,R_R0402-0201_DISCRETE_CS24702JB,4.7K,,R0402-0201,9400.00,2985.00,90.000,YES
R76,R_R0402-0201_DISCRETE_CS00002JB,0,,R0402-0201,1535.00,3465.00,0.000,YES
R77,R_R0402-0201_DISCRETE_CS00002JB,0,,R0402-0201,1535.00,3505.00,0.000,YES
R78,R_R0402-0201_DISCRETE_CS00002JB,0,,R0402-0201,1535.00,3355.00,0.000,YES
R79,R_R0402-0201_DISCRETE_CS00002JB,0,,R0402-0201,1535.00,3310.00,0.000,YES
R81,R_R0402-0201_DISCRETE_CS00002JB,0,,R0402-0201,10984.68,1604.13,0.000,NO
R82,R_R0402_DISCRETE_CS35362FB02_1/,53.6K,,R0402,6440.00,330.00,0.000,NO
R83,R_R0402-0201_DISCRETE_CS31002FB,10K,,R0402-0201,6885.00,325.00,180.000,NO
R90,R_R0402-0201_DISCRETE_CS21002FB,1K,,R0402-0201,8310.00,2745.00,270.000,YES
R91,R_R0402-0201_DISCRETE_CS21002FB,1K,,R0402-0201,8360.00,2745.00,270.000,YES
R92,R_R0402-0201_DISCRETE_CS21002FB,1K,,R0402-0201,8410.00,2745.00,270.000,YES
R93,R_R0402-0201_DISCRETE_CS21002FB,1K,,R0402-0201,8310.00,2645.00,90.000,YES
R94,R_R0402-0201_DISCRETE_CS21002FB,1K,,R0402-0201,8360.00,2645.00,90.000,YES
R95,R_R0402-0201_DISCRETE_CS21002FB,1K,,R0402-0201,8410.00,2645.00,90.000,YES
R96,R_R0402-0201_DISCRETE_CS11002FB,100,,R0402-0201,8985.00,2795.00,270.000,YES
R97,R_R0402-0201_DISCRETE_CS21002FB,1K,,R0402-0201,8100.00,3620.00,180.000,YES
R98,R_R0402-0201_DISCRETE_CS21002FB,1K,,R0402-0201,7990.00,3620.00,0.000,YES
R100,R_R0402-0201_DISCRETE_CS24702JB,4.7K,,R0402-0201,7990.00,3520.00,180.000,YES
R101,R_R0402-0201_DISCRETE_CS24702JB,4.7K,,R0402-0201,7990.00,3410.00,180.000,YES
R102,R_R0402-0201_DISCRETE_CS21002FB,1K,,R0402-0201,7990.00,3570.00,0.000,YES
R103,R_R0402-0201_DISCRETE_CS21002FB,1K,,R0402-0201,8100.00,3570.00,180.000,YES
R105,R_R0402-0201_DISCRETE_CS24702JB,4.7K,,R0402-0201,7465.00,3245.00,0.000,YES
R106,R_R0402-0201_DISCRETE_CS24702JB,4.7K,,R0402-0201,7465.00,3425.00,0.000,YES
R113,R_R0402-0201_DISCRETE_CS00002JB,0,,R0402-0201,7770.00,3695.00,0.000,YES
R117,R_R0402-0201_DISCRETE_CS03302FB,33,,R0402-0201,8160.00,2745.00,270.000,YES
R118,R_R0402-0201_DISCRETE_CS03302FB,33,,R0402-0201,8210.00,2745.00,270.000,YES
R125,R_R0402-0201_DISCRETE_CS24702JB,4.7K,,R0402-0201,7990.00,3465.00,180.000,YES
R126,R_R0402-0201_DISCRETE_CS24702JB,4.7K,,R0402-0201,8100.00,3410.00,180.000,YES
R127,R_R0402-0201_DISCRETE_CS24702JB,4.7K,,R0402-0201,7465.00,3345.00,0.000,YES
R128,R_R0402-0201_DISCRETE_CS24702JB,4.7K,,R0402-0201,7465.00,3285.00,0.000,YES
R129,R_R0402-0201_DISCRETE_CS24702JB,4.7K,,R0402-0201,7990.00,3300.00,180.000,YES
R130,R_R0402-0201_DISCRETE_CS24702JB,4.7K,,R0402-0201,7990.00,3350.00,180.000,YES
R131,R_R0402-0201_DISCRETE_CS24702JB,4.7K,,R0402-0201,7465.00,3532.00,0.000,YES
R132,R_R0402-0201_DISCRETE_CS24702JB,4.7K,,R0402-0201,7465.00,3477.00,0.000,YES
R133,R_R0402-0201_DISCRETE_CS21002FB,1K,,R0402-0201,8460.00,2745.00,270.000,YES
R134,R_R0402-0201_DISCRETE_CS21002FB,1K,,R0402-0201,8510.00,2745.00,270.000,YES
R135,R_R0402-0201_DISCRETE_CS21002FB,1K,,R0402-0201,8560.00,2745.00,270.000,YES
R136,R_R0402-0201_DISCRETE_CS21002FB,1K,,R0402-0201,8460.00,2645.00,90.000,YES
R137,R_R0402-0201_DISCRETE_CS21002FB,1K,,R0402-0201,8510.00,2645.00,90.000,YES
R138,R_R0402-0201_DISCRETE_CS21002FB,1K,,R0402-0201,8560.00,2645.00,90.000,YES
R139,R_R0402-0201_DISCRETE_CS03302FB,33,,R0402-0201,9195.00,2795.00,90.000,YES
R140,R_R0402-0201_DISCRETE_CS41002JB,100K,,R0402-0201,9080.00,3240.00,90.000,YES
R141,R_R0402-0201_DISCRETE_CS11502FB,150,,R0402-0201,9095.00,2960.00,270.000,YES
R142,R_R0402-0201_DISCRETE_CS24702JB,4.7K,,R0402-0201,9095.00,3340.00,270.000,YES
R144,R__R0402-0201_DISCRETE_CS00002J,0,,R0402-0201,10985.00,1475.00,0.000,NO
R145,R_R0402-0201_DISCRETE_CS00002JB,0,,R0402-0201,10985.32,1431.44,0.000,NO
R146,R_R0402-0201_DISCRETE_CS24702JB,4.7K,,R0402-0201,10984.68,1560.99,0.000,NO
R147,R_R0402-0201_DISCRETE_CS24702JB,4.7K,,R0402-0201,10984.68,1518.56,0.000,NO
R148,R_R0805_H26_DISCRETE_CS41744FA0,174K,,R0805_H26,11234.41,1282.56,90.000,NO
R149,R_R0402-0201_DISCRETE_CS31152FB,11.5K,,R0402-0201,11245.00,1384.57,180.000,NO
R150,R_R0402-0201_DISCRETE_CS24702JB,4.7K,,R0402-0201,11085.00,1405.00,90.000,NO
R151,R_R0402-0201_DISCRETE_CS00002JB,0,,R0402-0201,11125.00,1405.00,270.000,NO
R152,R_R0402-0201_DISCRETE_CS24702JB,4.7K,,R0402-0201,11100.00,1435.00,270.000,YES
R153,R_R0402-0201_DISCRETE_CS00002JB,0,,R0402-0201,11140.00,1435.00,90.000,YES
R156,R_R0402-0201_DISCRETE_CS00002JB,0,,R0402-0201,11020.00,1800.00,180.000,YES
R157,R_R0402-0201_DISCRETE_CS00002JB,0,,R0402-0201,11020.00,1835.00,180.000,YES
R158,R_R0402-0201_DISCRETE_CS00002JB,0,,R0402-0201,10770.00,1830.00,270.000,YES
R159,R_R0402-0201_DISCRETE_CS00002JB,0,,R0402-0201,10700.00,1875.00,270.000,YES
R160,R_R0402-0201_DISCRETE_CS00002JB,0,,R0402-0201,5387.80,4570.00,270.000,YES
R161,R_R0402-0201_DISCRETE_CS21002FB,1K,,R0402-0201,5475.00,3105.00,0.000,YES
R162,R_R0402-0201_DISCRETE_CS21002FB,1K,,R0402-0201,5385.00,3105.00,0.000,YES
R163,R_R0402-0201_DISCRETE_CS21002FB,1K,,R0402-0201,5295.00,3105.00,0.000,YES
R164,R_R0402-0201_DISCRETE_CS00002JB,0,,R0402-0201,5295.00,3005.00,180.000,YES
R165,R_R0402-0201_DISCRETE_CS00002JB,0,,R0402-0201,5385.00,3005.00,180.000,YES
R166,R_R0402-0201_DISCRETE_CS00002JB,0,,R0402-0201,5475.00,3005.00,180.000,YES
R167,R_R0402-0201_DISCRETE_CS00002JB,0,,R0402-0201,5770.00,4575.00,0.000,YES
R168,R_R0402-0201_DISCRETE_CS24702FB,4.7K,,R0402-0201,5775.00,4335.00,180.000,YES
R169,R_R0402-0201_DISCRETE_CS00002JB,0,,R0402-0201,5695.00,4490.00,270.000,YES
R170,R_R0402-0201_DISCRETE_CS00002JB,0,,R0402-0201,3812.99,4570.00,270.000,YES
R171,R_R0402-0201_DISCRETE_CS00002JB,0,,R0402-0201,3890.00,3005.00,180.000,YES
R172,R_R0402-0201_DISCRETE_CS00002JB,0,,R0402-0201,3715.00,3005.00,180.000,YES
R173,R_R0402-0201_DISCRETE_CS00002JB,0,,R0402-0201,3800.00,3005.00,180.000,YES
R174,R_R0402-0201_DISCRETE_CS21002FB,1K,,R0402-0201,3890.00,3095.00,0.000,YES
R175,R_R0402-0201_DISCRETE_CS21002FB,1K,,R0402-0201,3715.00,3095.00,0.000,YES
R176,R_R0402-0201_DISCRETE_CS21002FB,1K,,R0402-0201,3800.00,3095.00,0.000,YES
R177,R_R0402-0201_DISCRETE_CS00002JB,0,,R0402-0201,2238.19,4570.00,270.000,YES
R178,R_R0402-0201_DISCRETE_CS00002JB,0,,R0402-0201,2145.00,3005.00,180.000,YES
R179,R_R0402-0201_DISCRETE_CS00002JB,0,,R0402-0201,2230.00,3005.00,180.000,YES
R180,R_R0402-0201_DISCRETE_CS00002JB,0,,R0402-0201,2320.00,3005.00,180.000,YES
R181,R_R0402-0201_DISCRETE_CS21002FB,1K,,R0402-0201,2145.00,3095.00,0.000,YES
R182,R_R0402-0201_DISCRETE_CS21002FB,1K,,R0402-0201,2230.00,3095.00,0.000,YES
R183,R_R0402-0201_DISCRETE_CS21002FB,1K,,R0402-0201,2320.00,3095.00,0.000,YES
R184,R_R0402-0201_DISCRETE_CS03302FB,33,,R0402-0201,7465.00,3385.00,0.000,YES
R185,R_R0402-0201_DISCRETE_CS00002JB,0,,R0402-0201,8255.00,3340.00,0.000,YES
R187,R_R0402-0201_DISCRETE_CS41002JB,100K,,R0402-0201,9145.00,2960.00,270.000,YES
R188,R_R0402-0201_DISCRETE_CS41002JB,100K,,R0402-0201,8360.00,3235.00,0.000,YES
R189,R_R0402-0201_DISCRETE_CS00002JB,0,,R0402-0201,8360.00,3325.00,180.000,YES
R192,R_R0402-0201_DISCRETE_CS21002FB,1K,,R0402-0201,6869.81,3105.00,0.000,YES
R193,R_R0402-0201_DISCRETE_CS21002FB,1K,,R0402-0201,6959.81,3105.00,0.000,YES
R194,R_R0402-0201_DISCRETE_CS21002FB,1K,,R0402-0201,7049.81,3105.00,0.000,YES
R195,R_R0402-0201_DISCRETE_CS00002JB,0,,R0402-0201,6962.61,4570.00,270.000,YES
R196,R_R0402-0201_DISCRETE_CS00002JB,0,,R0402-0201,6869.81,3005.00,180.000,YES
R197,R_R0402-0201_DISCRETE_CS00002JB,0,,R0402-0201,6959.81,3005.00,180.000,YES
R198,R_R0402-0201_DISCRETE_CS00002JB,0,,R0402-0201,7049.81,3005.00,180.000,YES
R199,R_R0402-0201_DISCRETE_CS00002JB,0,,R0402-0201,9260.00,2795.00,90.000,YES
R200,R_R0402-0201_DISCRETE_CS00002JB,0,,R0402-0201,4255.19,4575.00,0.000,YES
R201,R_R0402-0201_DISCRETE_CS24702FB,4.7K,,R0402-0201,4200.19,4335.00,180.000,YES
R202,R_R0402-0201_DISCRETE_CS00002JB,0,,R0402-0201,4120.19,4490.00,270.000,YES
R203,R_R0402-0201_DISCRETE_CS31002JB,10K,,R0402-0201,3610.00,3020.00,90.000,YES
R398,R_R0805_DISCRETE_CS41744FA00_1/,174K,,R0805,5630.00,4495.00,270.000,YES
R399,R_R0402-0201_DISCRETE_CS31202FB,12K,,R0402-0201,5495.00,4490.00,90.000,YES
R5855,R__R0402-0201_DISCRETE_CS00002J,0,,R0402-0201,10580.00,1875.00,270.000,NO
R5856,R_R0402-0201_DISCRETE_CS00002JB,0,,R0402-0201,10535.00,1875.00,270.000,NO
R5860,R_R0402-0201_DISCRETE_CS00002JB,0,,R0402-0201,10768.00,4085.00,90.000,YES
R5861,R_R0402-0201_DISCRETE_CS00002JB,0,,R0402-0201,10788.43,3634.43,0.000,YES
R5862,R_R0402-0201_DISCRETE_CS00002JB,0,,R0402-0201,10803.00,4085.00,90.000,YES
R5863,R_R0402-0201_DISCRETE_CS00002JB,0,,R0402-0201,10788.43,3594.43,180.000,YES
R5864,R__R0402-0201_DISCRETE_CS00002J,0,,R0402-0201,10625.00,1875.00,270.000,NO
R5873,R_4P_R2512_4P_DISCRETE_SP_CS000,0.0005,,R2512_4P,1400.00,4145.00,0.000,YES
R5878,R_R0402-0201_DISCRETE_CS03302FB,33,,R0402-0201,7335.00,3385.00,0.000,YES
R5879,R_R0402-0201_DISCRETE_CS03302FB,33,,R0402-0201,7335.00,3285.00,0.000,YES
R5884,R_R0805_H26_DISCRETE_CS41744FA0,174K,,R0805_H26,11000.00,825.00,0.000,NO
R5885,R_R0402-0201_DISCRETE_CS31152FB,11.5K,,R0402-0201,11115.00,880.00,0.000,NO
R5886,R_R0805_H26_DISCRETE_CS41744FA0,174K,,R0805_H26,11660.00,1445.00,270.000,NO
R5887,R_R0402-0201_DISCRETE_CS31152FB,11.5K,,R0402-0201,11735.00,1115.00,0.000,NO
R5888,R_R0402-0201_DISCRETE_CS28452FB,8.45K,,R0402-0201,10910.00,955.00,90.000,NO
R5889,R_R0805_H26_DISCRETE_CS39534FA0,95.3K,,R0805_H26,10797.00,954.00,0.000,NO
R5890,R_R0805_H26_DISCRETE_CS00004JA0,0,,R0805_H26,11676.00,1933.00,90.000,YES
R5891,R_R0402-0201_DISCRETE_CS31002FB,10K,,R0402-0201,1660.40,2438.30,270.000,NO
R5892,R_R0402-0201_DISCRETE_CS21002FB,1K,,R0402-0201,1798.40,2168.30,180.000,NO
R5893,R_R0402_DISCRETE_CS11002FB07_1/,100,,R0402,1418.40,2333.30,90.000,NO
R5894,R_R0402_DISCRETE_CS41202FB05_1/,120K,,R0402,1605.57,2451.60,0.000,NO
R5895,R_R0603_DISCRETE_CS04993F909_1/,49.9,,R0603,1470.00,2383.00,270.000,NO
R5896,R_R0402_DISCRETE_CS37152FB05_1/,71.5K,,R0402,1605.57,2491.40,0.000,NO
R5897,R_R0402-0201_DISCRETE_CS31002FB,10K,,R0402-0201,1700.40,2438.30,90.000,NO
R5899,R_R0402-0201_DISCRETE_CS31002FB,10K,,R0402-0201,1605.57,2411.40,0.000,NO
R5900,R_R0402-0201_DISCRETE_CS34642FB,46.4K,,R0402-0201,1798.40,2423.30,0.000,NO
R5901,R_R0402-0201_DISCRETE_CS33742FB,37.4K,,R0402-0201,1799.00,2248.20,0.000,NO
R5902,R_R0402-0201_DISCRETE_CS32002FB,20K,,R0402-0201,1799.04,2277.23,180.000,YES
R5903,R_R0402-0201_DISCRETE_CS24702JB,4.7K,,R0402-0201,8520.00,3325.00,90.000,YES
R5904,R_R0402-0201_DISCRETE_CS00002JB,0,,R0402-0201,11320.00,1790.00,270.000,YES
R5905,R_R0402-0201_DISCRETE_CS00002JB,0,,R0402-0201,10480.00,1375.00,180.000,YES
R5906,R_R0402-0201_DISCRETE_CS00002JB,0,,R0402-0201,10435.00,1510.00,180.000,YES
R5907,R_R0402-0201_DISCRETE_CS00002JB,0,,R0402-0201,10825.00,1830.00,270.000,YES
R5908,R_R0402-0201_DISCRETE_CS00002JB,0,,R0402-0201,10735.00,1875.00,270.000,YES
R5909,R_R0402-0201_DISCRETE_CS31002JB,10K,,R0402-0201,8065.00,2810.00,270.000,YES
R5910,R_R0805_H26_DISCRETE_CS41744FA0,174K,,R0805_H26,11505.00,1770.00,0.000,YES
R5911,R_R0402-0201_DISCRETE_CS31152FB,11.5K,,R0402-0201,11467.60,1698.20,90.000,YES
R5915,R_R0805_H26_DISCRETE_CS41744FA0,174K,,R0805_H26,11105.00,1210.00,90.000,YES
R5916,R_R0402-0201_DISCRETE_CS31152FB,11.5K,,R0402-0201,11415.00,1160.00,270.000,YES
R5917,R_R0402-0201_DISCRETE_CS21002FB,1K,,R0402-0201,10775.00,1155.00,90.000,YES
R5918,R_R0805_H26_DISCRETE_CS52054FA0,2.05M,,R0805_H26,10535.00,1115.00,0.000,YES
R5919,R_R0402-0201_DISCRETE_CS34872FB,48.7K,,R0402-0201,11392.95,1437.34,180.000,YES
R5930,R_R0805_H26_DISCRETE_CS41744FA0,174K,,R0805_H26,10875.00,1350.00,180.000,YES
R5931,R_R0402-0201_DISCRETE_CS31152FB,11.5K,,R0402-0201,11045.00,1415.00,90.000,YES
R5932,R_R0805_H26_DISCRETE_CS41744FA0,174K,,R0805_H26,10897.72,1358.05,90.000,NO
R5933,R_R0402-0201_DISCRETE_CS31152FB,11.5K,,R0402-0201,10675.00,1580.00,90.000,YES
U1,LTC4307_MSOP8_IC_AL004307000_LT,LTC4307,,MSOP8,9371.96,3313.85,90.000,YES
U4,PCA9555_TSSOP24_IC_AL009555K04_,PCA9555,,TSSOP24,8340.00,2995.00,90.000,YES
U5,SN74LVC1G126DCKR_SOT353_0-65_2X,74LVC1G126SE-7,,SOT353_0-65_2X1-25,9085.00,3130.00,270.000,YES
U6,74AHC1G04GW_SOT353_0-65_2X1-25_,74LVC1G07SE-7,,SOT353_0-65_2X1-25,8285.00,3460.00,270.000,YES
U8,NC7SZD384_0_SC74AXA_IC_AL01G125,74LVC1G125GV,,SC74AXA,8485.00,3450.00,270.000,YES
U9,NC7SZD384_0_SC74AXA_IC_AL01G125,74LVC1G125GV,,SC74AXA,9200.00,3460.00,270.000,YES
U10,M24256BRMN6TP_SOIC8_IC_AKE53ZB0,M24256-BRMN6TP,,SOIC8,8725.00,3285.00,270.000,YES
U19,74LVC1G08W57_SOT25-5_0-95_3X1-6,74LVC1G08W5-7,,SOT25-5_0-95_3X1-6,11050.00,975.00,180.000,NO
U20,MOSFET_NCH_GDS_ESD_PROTECTED_SO,2N7002K,,SOT23_GDSXC,9050.00,3455.00,180.000,YES
U23,MOSFET_NCH_GDS_ESD_PROTECTED__1,DMN53D0L-7,,SOT23_GDSXC,5800.00,4480.00,0.000,YES
U24,MOSFET_NCH_GDS_ESD_PROTECTED__1,DMN53D0L-7,,SOT23_GDSXC,4225.19,4480.00,0.000,YES
U25,PCA9545PW_TSSOP20_0-65_6-5X4-4_,PCA9545APW,,TSSOP20_0-65_6-5X4-4,7715.00,3480.00,0.000,YES
U27,MOSFET_NCH_GDS_ESD_PROTECTED__1,DMN53D0L-7,,SOT23_GDSXC,8940.00,2950.00,180.000,YES
U29,M95256RDW6TP_TSSOP8_0-65_3X4-4X,M95256-RDW6TP,,TSSOP8_0-65_3X4-4XC,10745.54,1627.67,270.000,NO
U32,MP5025CGQVZ_QFN22_TH_3X5_IC_AL0,MP5022CGQV-Z,,QFN22_TH_3X5,1641.00,2262.00,180.000,NO
U36,MOSFET_NCH_GDS_ESD_PROTECTED__1,DMN53D0L-7,,SOT23_GDSXC,11485.00,1380.00,0.000,YES
U37,MOSFET_NCH_GDS_ESD_PROTECTED__1,DMN53D0L-7,,SOT23_GDSXC,10775.00,1045.00,90.000,YES
U39,MOSFET_NCH_GDS_ESD_PROTECTED__1,DMN53D0L-7,,SOT23_GDSXC,11100.00,1545.00,0.000,YES
U40,MOSFET_NCH_GDS_ESD_PROTECTED__1,DMN53D0L-7,,SOT23_GDSXC,10880.00,1530.00,270.000,YES
